FILE_TYPE = MULTI_PHYS_TABLE;

PART '74HC1G126GW'

{========================================================================================}
:VALUE         | PART_TYPE | MATERIAL | PART_NUMBER    = STANDARD | LIFECYCLE      | PART_NUMBER   | JEDEC_TYPE              | DESCRIPTION                    | MANUFTR | MANUF_PN      | RD_CMPLS_LVL | CMPLS_LVL | FROM_PJ    | CLASS | DIP_SMD | DATA                  | EE_CHECK_LIST | FP_ECN | PSL | CREATOR | STATUS | MSD  | ESD_CDM | ESD_HBM | ESD_MM | PIN_LENGTH_SHORT_PIN | PIN_LENGTH_LONG_PIN | CREATEDAY  ;
{========================================================================================}
 '74HC1G126GW' | 'SMLF'    | 'IC'     | 'AL1G0126007'(!) = ''       | ''               | 'AL1G0126007' |'TSSOP5_0-65_2-05X1-25'| 'IC(5P) 74HC1G126GW(SOT353)EP' | 'PHI'   | '74HC1G126GW' | 'EP(V1)'     | 'EP(V1)'  | 'S2D-ANDY' | 'IC'  | ''      | 'PHI_74HC1G126GW.pdf' | ''            | ''     | ''  | ''      | ''     | 'NA' | 'NA'    | 'NA'    | 'NA'   | '0 MILS'             | '0 MILS'            | '20100429'
 '74HC1G126GW' | 'SMLF'    | 'EMPTY'  | 'AL1G0126007'(!) = ''       | ''               | 'AL1G0126007' |'TSSOP5_0-65_2-05X1-25'| 'IC(5P) 74HC1G126GW(SOT353)EP' | 'PHI'   | '74HC1G126GW' | 'EP(V1)'     | 'EP(V1)'  | 'S2D-ANDY' | 'IC'  | ''      | 'PHI_74HC1G126GW.pdf' | ''            | ''     | ''  | ''      | ''     | 'NA' | 'NA'    | 'NA'    | 'NA'   | '0 MILS'             | '0 MILS'            | '20100429'

END_PART

END.

